FILE_TYPE = CONNECTIVITY;
{Allegro Design Entry HDL 16.6-p007 (v16-6-112F) 10/10/2012}
"PAGE_NUMBER" = 107;
0"NC";
1"P3E_CPU0_PE1_PCH_TXP<7:0>";
2"P3E_CPU0_PE1_SS_TXP<7:0>";
3"P3E_CPU0_PE1_PCH_TXN<7:0>";
4"P3E_CPU0_PE1_SS_TXN<7:0>";
5"P3E_CPU0_PE1_SS_C_TXP<7:0>";
6"P3E_CPU0_PE1_SS_TXP<7:0>";
7"P3E_CPU0_PE1_SS_C_TXN<7:0>";
8"P3E_CPU0_PE1_SS_TXN<7:0>";
9"P3E_CPU0_PE1_SS_RXP<7:0>";
10"P3E_CPU0_PE1_PCH_RXP<7:0>";
11"P3E_CPU0_PE1_SS_RXN<7:0>";
12"P3E_CPU0_PE1_PCH_RXN<7:0>";
13"P3E_CPU0_PE1_SS_R_RXP<7:0>";
14"P3E_CPU0_PE1_SS_RXN<7:0>";
15"P3E_CPU0_PE1_SS_RXP<7:0>";
16"P3E_CPU0_PE1_SS_R_RXN<7:0>";
17"P3E_CPU0_PE1_SS_R_RXN<0>";
18"P3E_CPU0_PE1_SS_R_RXN<2>";
19"P3E_CPU0_PE1_SS_R_RXN<4>";
20"P3E_CPU0_PE1_SS_R_RXN<6>";
21"P3E_CPU0_PE1_SS_R_RXN<1>";
22"P3E_CPU0_PE1_SS_R_RXN<3>";
23"P3E_CPU0_PE1_SS_R_RXN<5>";
24"P3E_CPU0_PE1_SS_R_RXN<7>";
25"P3E_CPU0_PE1_SS_RXN<0>";
26"P3E_CPU0_PE1_SS_R_RXP<0>";
27"P3E_CPU0_PE1_SS_R_RXP<1>";
28"P3E_CPU0_PE1_SS_RXP<0>";
29"P3E_CPU0_PE1_SS_RXP<1>";
30"P3E_CPU0_PE1_SS_RXN<2>";
31"P3E_CPU0_PE1_SS_RXN<1>";
32"P3E_CPU0_PE1_SS_RXN<3>";
33"P3E_CPU0_PE1_SS_R_RXP<2>";
34"P3E_CPU0_PE1_SS_RXN<4>";
35"P3E_CPU0_PE1_SS_RXN<6>";
36"P3E_CPU0_PE1_SS_RXN<5>";
37"P3E_CPU0_PE1_SS_R_RXP<4>";
38"P3E_CPU0_PE1_SS_R_RXP<6>";
39"P3E_CPU0_PE1_SS_R_RXP<3>";
40"P3E_CPU0_PE1_SS_R_RXP<5>";
41"P3E_CPU0_PE1_SS_RXP<2>";
42"P3E_CPU0_PE1_SS_RXP<3>";
43"P3E_CPU0_PE1_SS_RXP<4>";
44"P3E_CPU0_PE1_SS_RXP<6>";
45"P3E_CPU0_PE1_SS_RXP<5>";
46"P3E_CPU0_PE1_PCH_RXN<0>";
47"P3E_CPU0_PE1_SS_RXN<0>";
48"P3E_CPU0_PE1_PCH_RXP<0>";
49"P3E_CPU0_PE1_SS_RXP<0>";
50"P3E_CPU0_PE1_SS_RXN<7>";
51"P3E_CPU0_PE1_SS_R_RXP<7>";
52"P3E_CPU0_PE1_SS_RXP<7>";
53"P3E_CPU0_PE1_PCH_RXN<1>";
54"P3E_CPU0_PE1_PCH_RXN<2>";
55"P3E_CPU0_PE1_PCH_RXN<3>";
56"P3E_CPU0_PE1_SS_RXN<2>";
57"P3E_CPU0_PE1_SS_RXN<1>";
58"P3E_CPU0_PE1_SS_RXN<3>";
59"P3E_CPU0_PE1_PCH_RXN<4>";
60"P3E_CPU0_PE1_PCH_RXN<5>";
61"P3E_CPU0_PE1_SS_RXN<4>";
62"P3E_CPU0_PE1_SS_RXN<5>";
63"P3E_CPU0_PE1_PCH_RXP<1>";
64"P3E_CPU0_PE1_PCH_RXP<2>";
65"P3E_CPU0_PE1_PCH_RXP<3>";
66"P3E_CPU0_PE1_PCH_RXP<4>";
67"P3E_CPU0_PE1_PCH_RXP<5>";
68"P3E_CPU0_PE1_SS_RXP<2>";
69"P3E_CPU0_PE1_SS_RXP<1>";
70"P3E_CPU0_PE1_SS_RXP<3>";
71"P3E_CPU0_PE1_SS_RXP<4>";
72"P3E_CPU0_PE1_SS_RXP<5>";
73"P3E_CPU0_PE1_PCH_RXN<6>";
74"P3E_CPU0_PE1_PCH_RXN<7>";
75"P3E_CPU0_PE1_SS_RXN<6>";
76"P3E_CPU0_PE1_SS_RXN<7>";
77"P3E_CPU0_PE1_PCH_RXP<6>";
78"P3E_CPU0_PE1_PCH_RXP<7>";
79"P3E_CPU0_PE1_SS_RXP<6>";
80"P3E_CPU0_PE1_SS_RXP<7>";
81"P3E_CPU0_PE1_SS_TXN<6>";
82"P3E_CPU0_PE1_SS_TXN<0>";
83"P3E_CPU0_PE1_SS_TXN<1>";
84"P3E_CPU0_PE1_SS_TXN<2>";
85"P3E_CPU0_PE1_SS_TXN<3>";
86"P3E_CPU0_PE1_SS_TXN<4>";
87"P3E_CPU0_PE1_SS_TXN<5>";
88"P3E_CPU0_PE1_SS_TXN<7>";
89"P3E_CPU0_PE1_SS_C_TXN<0>";
90"P3E_CPU0_PE1_SS_C_TXN<1>";
91"P3E_CPU0_PE1_SS_TXP<0>";
92"P3E_CPU0_PE1_SS_C_TXN<2>";
93"P3E_CPU0_PE1_SS_C_TXN<4>";
94"P3E_CPU0_PE1_SS_TXP<2>";
95"P3E_CPU0_PE1_SS_C_TXN<3>";
96"P3E_CPU0_PE1_SS_TXP<4>";
97"P3E_CPU0_PE1_SS_TXP<1>";
98"P3E_CPU0_PE1_SS_TXP<3>";
99"P3E_CPU0_PE1_SS_C_TXP<0>";
100"P3E_CPU0_PE1_SS_C_TXP<1>";
101"P3E_CPU0_PE1_SS_C_TXP<2>";
102"P3E_CPU0_PE1_SS_C_TXP<3>";
103"P3E_CPU0_PE1_SS_C_TXP<4>";
104"P3E_CPU0_PE1_SS_C_TXN<6>";
105"P3E_CPU0_PE1_SS_C_TXN<5>";
106"P3E_CPU0_PE1_SS_TXP<6>";
107"P3E_CPU0_PE1_SS_C_TXN<7>";
108"P3E_CPU0_PE1_SS_TXP<5>";
109"P3E_CPU0_PE1_SS_TXP<7>";
110"P3E_CPU0_PE1_SS_C_TXP<5>";
111"P3E_CPU0_PE1_SS_C_TXP<6>";
112"P3E_CPU0_PE1_SS_C_TXP<7>";
113"P3E_CPU0_PE1_SS_TXN<0>";
114"P3E_CPU0_PE1_SS_TXN<1>";
115"P3E_CPU0_PE1_SS_TXN<3>";
116"P3E_CPU0_PE1_SS_TXN<2>";
117"P3E_CPU0_PE1_PCH_TXN<0>";
118"P3E_CPU0_PE1_PCH_TXN<2>";
119"P3E_CPU0_PE1_PCH_TXN<1>";
120"P3E_CPU0_PE1_PCH_TXN<3>";
121"P3E_CPU0_PE1_SS_TXP<0>";
122"P3E_CPU0_PE1_SS_TXP<2>";
123"P3E_CPU0_PE1_SS_TXP<1>";
124"P3E_CPU0_PE1_SS_TXP<3>";
125"P3E_CPU0_PE1_PCH_TXP<0>";
126"P3E_CPU0_PE1_PCH_TXP<2>";
127"P3E_CPU0_PE1_PCH_TXP<1>";
128"P3E_CPU0_PE1_PCH_TXP<3>";
129"P3E_CPU0_PE1_SS_TXN<4>";
130"P3E_CPU0_PE1_SS_TXN<6>";
131"P3E_CPU0_PE1_SS_TXN<5>";
132"P3E_CPU0_PE1_SS_TXN<7>";
133"P3E_CPU0_PE1_PCH_TXN<4>";
134"P3E_CPU0_PE1_PCH_TXN<5>";
135"P3E_CPU0_PE1_PCH_TXN<6>";
136"P3E_CPU0_PE1_PCH_TXN<7>";
137"P3E_CPU0_PE1_SS_TXP<4>";
138"P3E_CPU0_PE1_SS_TXP<6>";
139"P3E_CPU0_PE1_SS_TXP<5>";
140"P3E_CPU0_PE1_SS_TXP<7>";
141"P3E_CPU0_PE1_PCH_TXP<4>";
142"P3E_CPU0_PE1_PCH_TXP<5>";
143"P3E_CPU0_PE1_PCH_TXP<6>";
144"P3E_CPU0_PE1_PCH_TXP<7>";
%"TAP"
"3","(-5525,2125)","0","mstr_standard","I198";
;
BODY_TYPE"PLUMBING"
CDS_LIB"mstr_standard"
HDL_TAP"TRUE";
"B \NAC \NWC"4;
"S \NAC"
BN"0"113;
%"TAP"
"3","(-5725,2125)","0","mstr_standard","I199";
;
CDS_LIB"mstr_standard"
BODY_TYPE"PLUMBING"
HDL_TAP"TRUE";
"B \NAC \NWC"4;
"S \NAC"
BN"1"114;
%"TAP"
"3","(-5925,2125)","0","mstr_standard","I200";
;
BODY_TYPE"PLUMBING"
CDS_LIB"mstr_standard"
HDL_TAP"TRUE";
"B \NAC \NWC"4;
"S \NAC"
BN"2"116;
%"TAP"
"3","(-6125,2125)","0","mstr_standard","I201";
;
BODY_TYPE"PLUMBING"
CDS_LIB"mstr_standard"
HDL_TAP"TRUE";
"B \NAC \NWC"4;
"S \NAC"
BN"3"115;
%"TAP"
"3","(-6325,2125)","0","mstr_standard","I202";
;
HDL_TAP"TRUE"
BODY_TYPE"PLUMBING"
CDS_LIB"mstr_standard";
"B \NAC \NWC"4;
"S \NAC"
BN"4"129;
%"TAP"
"3","(-6525,2125)","0","mstr_standard","I203";
;
BODY_TYPE"PLUMBING"
CDS_LIB"mstr_standard"
HDL_TAP"TRUE";
"B \NAC \NWC"4;
"S \NAC"
BN"5"131;
%"TAP"
"3","(-6725,2125)","0","mstr_standard","I204";
;
BODY_TYPE"PLUMBING"
CDS_LIB"mstr_standard"
HDL_TAP"TRUE";
"B \NAC \NWC"4;
"S \NAC"
BN"6"130;
%"TAP"
"3","(-6925,2125)","0","mstr_standard","I205";
;
BODY_TYPE"PLUMBING"
CDS_LIB"mstr_standard"
HDL_TAP"TRUE";
"B \NAC \NWC"4;
"S \NAC"
BN"7"132;
%"CAP"
"1","(-5525,1875)","2","mstr_discrete","I207";
;
$SEC"1"
CDS_SEC"1"
CDS_LOCATION"C3P13"
CDS_LIB"mstr_discrete"
MATERIAL"X7R"
VOLTAGE"16V"
PACK_TYPE"0402"
TOLERANCE"10%"
VALUE"0.22UF"
PART_NUMBER"A36096-155"
LOCATION"C3P13";
"A"
$PN"1"113;
"B"
$PN"2"117;
%"CAP"
"1","(-5725,1575)","2","mstr_discrete","I208";
;
CDS_LOCATION"C3P17"
$SEC"1"
CDS_SEC"1"
CDS_LIB"mstr_discrete"
VOLTAGE"16V"
VALUE"0.22UF"
LOCATION"C3P17"
TOLERANCE"10%"
MATERIAL"X7R"
PACK_TYPE"0402"
PART_NUMBER"A36096-155";
"A"
$PN"1"114;
"B"
$PN"2"119;
%"TAP"
"7","(-5525,1325)","0","mstr_standard","I210";
;
HDL_TAP"TRUE"
BODY_TYPE"PLUMBING"
CDS_LIB"mstr_standard";
"B \NAC \NWC"3;
"S \NAC"
BN"0"117;
%"TAP"
"3","(-5475,1125)","0","mstr_standard","I211";
;
CDS_LIB"mstr_standard"
BODY_TYPE"PLUMBING"
HDL_TAP"TRUE";
"B \NAC \NWC"2;
"S \NAC"
BN"0"121;
%"CAP"
"1","(-5475,875)","2","mstr_discrete","I212";
;
$SEC"1"
CDS_SEC"1"
CDS_LOCATION"C3P11"
CDS_LIB"mstr_discrete"
MATERIAL"X7R"
VOLTAGE"16V"
TOLERANCE"10%"
PACK_TYPE"0402"
VALUE"0.22UF"
PART_NUMBER"A36096-155"
LOCATION"C3P11";
"A"
$PN"1"121;
"B"
$PN"2"125;
%"TAP"
"7","(-5725,1325)","0","mstr_standard","I213";
;
HDL_TAP"TRUE"
BODY_TYPE"PLUMBING"
CDS_LIB"mstr_standard";
"B \NAC \NWC"3;
"S \NAC"
BN"1"119;
%"TAP"
"3","(-5675,1125)","0","mstr_standard","I214";
;
BODY_TYPE"PLUMBING"
CDS_LIB"mstr_standard"
HDL_TAP"TRUE";
"B \NAC \NWC"2;
"S \NAC"
BN"1"123;
%"CAP"
"1","(-5925,1900)","2","mstr_discrete","I215";
;
$SEC"1"
CDS_SEC"1"
CDS_LIB"mstr_discrete"
CDS_LOCATION"C3P20"
LOCATION"C3P20"
TOLERANCE"10%"
VOLTAGE"16V"
MATERIAL"X7R"
PACK_TYPE"0402"
VALUE"0.22UF"
PART_NUMBER"A36096-155";
"A"
$PN"1"116;
"B"
$PN"2"118;
%"CAP"
"1","(-6125,1575)","2","mstr_discrete","I216";
;
CDS_LIB"mstr_discrete"
CDS_SEC"1"
$SEC"1"
CDS_LOCATION"C3P25"
LOCATION"C3P25"
VALUE"0.22UF"
VOLTAGE"16V"
TOLERANCE"10%"
MATERIAL"X7R"
PACK_TYPE"0402"
PART_NUMBER"A36096-155";
"A"
$PN"1"115;
"B"
$PN"2"120;
%"TAP"
"7","(-5925,1325)","0","mstr_standard","I217";
;
HDL_TAP"TRUE"
BODY_TYPE"PLUMBING"
CDS_LIB"mstr_standard";
"B \NAC \NWC"3;
"S \NAC"
BN"2"118;
%"TAP"
"3","(-5875,1125)","0","mstr_standard","I218";
;
CDS_LIB"mstr_standard"
BODY_TYPE"PLUMBING"
HDL_TAP"TRUE";
"B \NAC \NWC"2;
"S \NAC"
BN"2"122;
%"CAP"
"1","(-5875,875)","2","mstr_discrete","I219";
;
CDS_SEC"1"
$SEC"1"
CDS_LIB"mstr_discrete"
CDS_LOCATION"C3P18"
LOCATION"C3P18"
VALUE"0.22UF"
TOLERANCE"10%"
VOLTAGE"16V"
MATERIAL"X7R"
PACK_TYPE"0402"
PART_NUMBER"A36096-155";
"A"
$PN"1"122;
"B"
$PN"2"126;
%"TAP"
"3","(-6075,1125)","0","mstr_standard","I220";
;
CDS_LIB"mstr_standard"
BODY_TYPE"PLUMBING"
HDL_TAP"TRUE";
"B \NAC \NWC"2;
"S \NAC"
BN"3"124;
%"TAP"
"7","(-6125,1325)","0","mstr_standard","I221";
;
HDL_TAP"TRUE"
CDS_LIB"mstr_standard"
BODY_TYPE"PLUMBING";
"B \NAC \NWC"3;
"S \NAC"
BN"3"120;
%"TAP"
"3","(-6275,1125)","0","mstr_standard","I222";
;
HDL_TAP"TRUE"
BODY_TYPE"PLUMBING"
CDS_LIB"mstr_standard";
"B \NAC \NWC"2;
"S \NAC"
BN"4"137;
%"CAP"
"1","(-6275,875)","2","mstr_discrete","I223";
;
$SEC"1"
CDS_SEC"1"
CDS_LOCATION"C3P27"
CDS_LIB"mstr_discrete"
MATERIAL"X7R"
VOLTAGE"16V"
PACK_TYPE"0402"
TOLERANCE"10%"
VALUE"0.22UF"
PART_NUMBER"A36096-155"
LOCATION"C3P27";
"A"
$PN"1"137;
"B"
$PN"2"141;
%"TAP"
"7","(-5475,325)","0","mstr_standard","I224";
;
HDL_TAP"TRUE"
BODY_TYPE"PLUMBING"
CDS_LIB"mstr_standard";
"B \NAC \NWC"1;
"S \NAC"
BN"0"125;
%"CAP"
"1","(-5675,575)","2","mstr_discrete","I226";
;
CDS_SEC"1"
$SEC"1"
CDS_LOCATION"C3P15"
CDS_LIB"mstr_discrete"
LOCATION"C3P15"
TOLERANCE"10%"
VOLTAGE"16V"
VALUE"0.22UF"
MATERIAL"X7R"
PACK_TYPE"0402"
PART_NUMBER"A36096-155";
"A"
$PN"1"123;
"B"
$PN"2"127;
%"TAP"
"7","(-5675,325)","0","mstr_standard","I227";
;
HDL_TAP"TRUE"
BODY_TYPE"PLUMBING"
CDS_LIB"mstr_standard";
"B \NAC \NWC"1;
"S \NAC"
BN"1"127;
%"TAP"
"7","(-5875,325)","0","mstr_standard","I228";
;
HDL_TAP"TRUE"
BODY_TYPE"PLUMBING"
CDS_LIB"mstr_standard";
"B \NAC \NWC"1;
"S \NAC"
BN"2"126;
%"CAP"
"1","(-6075,575)","2","mstr_discrete","I229";
;
CDS_SEC"1"
$SEC"1"
CDS_LIB"mstr_discrete"
CDS_LOCATION"C3P23"
MATERIAL"X7R"
VOLTAGE"16V"
PACK_TYPE"0402"
TOLERANCE"10%"
VALUE"0.22UF"
PART_NUMBER"A36096-155"
LOCATION"C3P23";
"A"
$PN"1"124;
"B"
$PN"2"128;
%"TAP"
"7","(-6075,325)","0","mstr_standard","I230";
;
HDL_TAP"TRUE"
BODY_TYPE"PLUMBING"
CDS_LIB"mstr_standard";
"B \NAC \NWC"1;
"S \NAC"
BN"3"128;
%"TAP"
"7","(-6275,325)","0","mstr_standard","I231";
;
HDL_TAP"TRUE"
BODY_TYPE"PLUMBING"
CDS_LIB"mstr_standard";
"B \NAC \NWC"1;
"S \NAC"
BN"4"141;
%"CAP"
"1","(-6325,1875)","2","mstr_discrete","I232";
;
$SEC"1"
CDS_SEC"1"
CDS_LIB"mstr_discrete"
CDS_LOCATION"C3P28"
MATERIAL"X7R"
VOLTAGE"16V"
PACK_TYPE"0402"
TOLERANCE"10%"
VALUE"0.22UF"
LOCATION"C3P28"
PART_NUMBER"A36096-155";
"A"
$PN"1"129;
"B"
$PN"2"133;
%"TAP"
"7","(-6325,1325)","0","mstr_standard","I233";
;
HDL_TAP"TRUE"
CDS_LIB"mstr_standard"
BODY_TYPE"PLUMBING";
"B \NAC \NWC"3;
"S \NAC"
BN"4"133;
%"CAP"
"1","(-6525,1575)","2","mstr_discrete","I234";
;
CDS_LOCATION"C3P32"
CDS_LIB"mstr_discrete"
CDS_SEC"1"
$SEC"1"
MATERIAL"X7R"
VOLTAGE"16V"
PACK_TYPE"0402"
TOLERANCE"10%"
VALUE"0.22UF"
PART_NUMBER"A36096-155"
LOCATION"C3P32";
"A"
$PN"1"131;
"B"
$PN"2"134;
%"CAP"
"1","(-6725,1875)","2","mstr_discrete","I235";
;
$SEC"1"
CDS_SEC"1"
CDS_LIB"mstr_discrete"
CDS_LOCATION"C3P37"
TOLERANCE"10%"
VOLTAGE"16V"
MATERIAL"X7R"
PACK_TYPE"0402"
VALUE"0.22UF"
PART_NUMBER"A36096-155"
LOCATION"C3P37";
"A"
$PN"1"130;
"B"
$PN"2"135;
%"TAP"
"7","(-6525,1325)","0","mstr_standard","I236";
;
HDL_TAP"TRUE"
BODY_TYPE"PLUMBING"
CDS_LIB"mstr_standard";
"B \NAC \NWC"3;
"S \NAC"
BN"5"134;
%"TAP"
"3","(-6475,1125)","0","mstr_standard","I237";
;
CDS_LIB"mstr_standard"
BODY_TYPE"PLUMBING"
HDL_TAP"TRUE";
"B \NAC \NWC"2;
"S \NAC"
BN"5"139;
%"TAP"
"3","(-6675,1125)","0","mstr_standard","I238";
;
BODY_TYPE"PLUMBING"
CDS_LIB"mstr_standard"
HDL_TAP"TRUE";
"B \NAC \NWC"2;
"S \NAC"
BN"6"138;
%"TAP"
"7","(-6725,1325)","0","mstr_standard","I239";
;
HDL_TAP"TRUE"
BODY_TYPE"PLUMBING"
CDS_LIB"mstr_standard";
"B \NAC \NWC"3;
"S \NAC"
BN"6"135;
%"CAP"
"1","(-6675,875)","2","mstr_discrete","I240";
;
CDS_SEC"1"
$SEC"1"
CDS_LIB"mstr_discrete"
CDS_LOCATION"C3P35"
TOLERANCE"10%"
VOLTAGE"16V"
MATERIAL"X7R"
LOCATION"C3P35"
VALUE"0.22UF"
PACK_TYPE"0402"
PART_NUMBER"A36096-155";
"A"
$PN"1"138;
"B"
$PN"2"143;
%"CAP"
"1","(-6925,1575)","2","mstr_discrete","I241";
;
CDS_SEC"1"
CDS_LIB"mstr_discrete"
$SEC"1"
CDS_LOCATION"C3P40"
LOCATION"C3P40"
VALUE"0.22UF"
VOLTAGE"16V"
TOLERANCE"10%"
MATERIAL"X7R"
PACK_TYPE"0402"
PART_NUMBER"A36096-155";
"A"
$PN"1"132;
"B"
$PN"2"136;
%"TAP"
"7","(-6925,1325)","0","mstr_standard","I242";
;
HDL_TAP"TRUE"
BODY_TYPE"PLUMBING"
CDS_LIB"mstr_standard";
"B \NAC \NWC"3;
"S \NAC"
BN"7"136;
%"TAP"
"3","(-6875,1125)","0","mstr_standard","I243";
;
BODY_TYPE"PLUMBING"
CDS_LIB"mstr_standard"
HDL_TAP"TRUE";
"B \NAC \NWC"2;
"S \NAC"
BN"7"140;
%"CAP"
"1","(-6475,575)","2","mstr_discrete","I245";
;
CDS_LOCATION"C3P30"
CDS_SEC"1"
$SEC"1"
CDS_LIB"mstr_discrete"
TOLERANCE"10%"
VOLTAGE"16V"
PACK_TYPE"0402"
MATERIAL"X7R"
VALUE"0.22UF"
PART_NUMBER"A36096-155"
LOCATION"C3P30";
"A"
$PN"1"139;
"B"
$PN"2"142;
%"TAP"
"7","(-6475,325)","0","mstr_standard","I246";
;
HDL_TAP"TRUE"
BODY_TYPE"PLUMBING"
CDS_LIB"mstr_standard";
"B \NAC \NWC"1;
"S \NAC"
BN"5"142;
%"TAP"
"7","(-6675,325)","0","mstr_standard","I247";
;
HDL_TAP"TRUE"
BODY_TYPE"PLUMBING"
CDS_LIB"mstr_standard";
"B \NAC \NWC"1;
"S \NAC"
BN"6"143;
%"CAP"
"1","(-6875,575)","2","mstr_discrete","I248";
;
CDS_LIB"mstr_discrete"
$SEC"1"
CDS_SEC"1"
CDS_LOCATION"C3P39"
LOCATION"C3P39"
VALUE"0.22UF"
TOLERANCE"10%"
VOLTAGE"16V"
PACK_TYPE"0402"
MATERIAL"X7R"
PART_NUMBER"A36096-155";
"A"
$PN"1"140;
"B"
$PN"2"144;
%"TAP"
"7","(-6875,325)","0","mstr_standard","I249";
;
HDL_TAP"TRUE"
BODY_TYPE"PLUMBING"
CDS_LIB"mstr_standard";
"B \NAC \NWC"1;
"S \NAC"
BN"7"144;
%"TAP"
"3","(-1950,2075)","0","mstr_standard","I250";
;
CDS_LIB"mstr_standard"
BODY_TYPE"PLUMBING"
HDL_TAP"TRUE";
"B \NAC \NWC"12;
"S \NAC"
BN"0"46;
%"TAP"
"3","(-2150,2075)","0","mstr_standard","I251";
;
HDL_TAP"TRUE"
CDS_LIB"mstr_standard"
BODY_TYPE"PLUMBING";
"B \NAC \NWC"12;
"S \NAC"
BN"1"53;
%"TAP"
"3","(-2350,2075)","0","mstr_standard","I252";
;
HDL_TAP"TRUE"
CDS_LIB"mstr_standard"
BODY_TYPE"PLUMBING";
"B \NAC \NWC"12;
"S \NAC"
BN"2"54;
%"TAP"
"3","(-2550,2075)","0","mstr_standard","I253";
;
CDS_LIB"mstr_standard"
BODY_TYPE"PLUMBING"
HDL_TAP"TRUE";
"B \NAC \NWC"12;
"S \NAC"
BN"3"55;
%"TAP"
"3","(-2750,2075)","0","mstr_standard","I254";
;
CDS_LIB"mstr_standard"
BODY_TYPE"PLUMBING"
HDL_TAP"TRUE";
"B \NAC \NWC"12;
"S \NAC"
BN"4"59;
%"CAP"
"1","(-1950,1825)","2","mstr_discrete","I257";
;
CDS_SEC"1"
SEC"1"
SEC_TYPE"0402"
CDS_LIB"mstr_discrete"
CDS_LOCATION"C2U4"
PART_NUMBER"A36096-155"
VOLTAGE"16V"
MATERIAL"X7R"
TOLERANCE"10%"
VALUE"0.22UF"
LOCATION"C2U4"
PACK_TYPE"0402";
"A"
$PN"1"46;
"B"
$PN"2"47;
%"TAP"
"3","(-1900,1075)","0","mstr_standard","I258";
;
CDS_LIB"mstr_standard"
BODY_TYPE"PLUMBING"
HDL_TAP"TRUE";
"B \NAC \NWC"10;
"S \NAC"
BN"0"48;
%"TAP"
"7","(-1950,1275)","0","mstr_standard","I259";
;
HDL_TAP"TRUE"
CDS_LIB"mstr_standard"
BODY_TYPE"PLUMBING";
"B \NAC \NWC"11;
"S \NAC"
BN"0"47;
%"CAP"
"1","(-2150,1525)","2","mstr_discrete","I260";
;
CDS_SEC"1"
CDS_LOCATION"C2U6"
SEC"1"
SEC_TYPE"0402"
CDS_LIB"mstr_discrete"
PART_NUMBER"A36096-155"
VALUE"0.22UF"
LOCATION"C2U6"
VOLTAGE"16V"
MATERIAL"X7R"
TOLERANCE"10%"
PACK_TYPE"0402";
"A"
$PN"1"53;
"B"
$PN"2"57;
%"TAP"
"3","(-2100,1075)","0","mstr_standard","I261";
;
HDL_TAP"TRUE"
CDS_LIB"mstr_standard"
BODY_TYPE"PLUMBING";
"B \NAC \NWC"10;
"S \NAC"
BN"1"63;
%"TAP"
"7","(-2150,1275)","0","mstr_standard","I262";
;
HDL_TAP"TRUE"
BODY_TYPE"PLUMBING"
CDS_LIB"mstr_standard";
"B \NAC \NWC"11;
"S \NAC"
BN"1"57;
%"TAP"
"3","(-2300,1075)","0","mstr_standard","I263";
;
HDL_TAP"TRUE"
CDS_LIB"mstr_standard"
BODY_TYPE"PLUMBING";
"B \NAC \NWC"10;
"S \NAC"
BN"2"64;
%"CAP"
"1","(-2350,1825)","2","mstr_discrete","I264";
;
CDS_SEC"1"
SEC"1"
SEC_TYPE"0402"
CDS_LOCATION"C2U8"
CDS_LIB"mstr_discrete"
LOCATION"C2U8"
VOLTAGE"16V"
TOLERANCE"10%"
PACK_TYPE"0402"
MATERIAL"X7R"
PART_NUMBER"A36096-155"
VALUE"0.22UF";
"A"
$PN"1"54;
"B"
$PN"2"56;
%"CAP"
"1","(-2750,1825)","2","mstr_discrete","I265";
;
CDS_SEC"1"
SEC"1"
SEC_TYPE"0402"
CDS_LIB"mstr_discrete"
CDS_LOCATION"C2U12"
VALUE"0.22UF"
VOLTAGE"16V"
MATERIAL"X7R"
TOLERANCE"10%"
LOCATION"C2U12"
PACK_TYPE"0402"
PART_NUMBER"A36096-155";
"A"
$PN"1"59;
"B"
$PN"2"61;
%"TAP"
"7","(-2350,1275)","0","mstr_standard","I266";
;
HDL_TAP"TRUE"
BODY_TYPE"PLUMBING"
CDS_LIB"mstr_standard";
"B \NAC \NWC"11;
"S \NAC"
BN"2"56;
%"CAP"
"1","(-2550,1525)","2","mstr_discrete","I267";
;
CDS_SEC"1"
CDS_LIB"mstr_discrete"
SEC_TYPE"0402"
SEC"1"
CDS_LOCATION"C2U10"
PART_NUMBER"A36096-155"
VALUE"0.22UF"
LOCATION"C2U10"
VOLTAGE"16V"
TOLERANCE"10%"
MATERIAL"X7R"
PACK_TYPE"0402";
"A"
$PN"1"55;
"B"
$PN"2"58;
%"TAP"
"7","(-2550,1275)","0","mstr_standard","I268";
;
HDL_TAP"TRUE"
BODY_TYPE"PLUMBING"
CDS_LIB"mstr_standard";
"B \NAC \NWC"11;
"S \NAC"
BN"3"58;
%"TAP"
"3","(-2500,1075)","0","mstr_standard","I269";
;
CDS_LIB"mstr_standard"
BODY_TYPE"PLUMBING"
HDL_TAP"TRUE";
"B \NAC \NWC"10;
"S \NAC"
BN"3"65;
%"TAP"
"3","(-2700,1075)","0","mstr_standard","I270";
;
BODY_TYPE"PLUMBING"
CDS_LIB"mstr_standard"
HDL_TAP"TRUE";
"B \NAC \NWC"10;
"S \NAC"
BN"4"66;
%"TAP"
"7","(-2750,1275)","0","mstr_standard","I271";
;
HDL_TAP"TRUE"
BODY_TYPE"PLUMBING"
CDS_LIB"mstr_standard";
"B \NAC \NWC"11;
"S \NAC"
BN"4"61;
%"CAP"
"1","(-1900,825)","2","mstr_discrete","I272";
;
CDS_SEC"1"
SEC"1"
SEC_TYPE"0402"
CDS_LOCATION"C2U3"
CDS_LIB"mstr_discrete"
TOLERANCE"10%"
VOLTAGE"16V"
MATERIAL"X7R"
PART_NUMBER"A36096-155"
PACK_TYPE"0402"
VALUE"0.22UF"
LOCATION"C2U3";
"A"
$PN"1"48;
"B"
$PN"2"49;
%"TAP"
"7","(-1900,275)","0","mstr_standard","I273";
;
HDL_TAP"TRUE"
BODY_TYPE"PLUMBING"
CDS_LIB"mstr_standard";
"B \NAC \NWC"9;
"S \NAC"
BN"0"49;
%"CAP"
"1","(-2100,525)","2","mstr_discrete","I274";
;
CDS_SEC"1"
SEC"1"
CDS_LOCATION"C2U5"
SEC_TYPE"0402"
CDS_LIB"mstr_discrete"
PART_NUMBER"A36096-155"
LOCATION"C2U5"
VOLTAGE"16V"
VALUE"0.22UF"
TOLERANCE"10%"
PACK_TYPE"0402"
MATERIAL"X7R";
"A"
$PN"1"63;
"B"
$PN"2"69;
%"TAP"
"7","(-2100,275)","0","mstr_standard","I275";
;
HDL_TAP"TRUE"
CDS_LIB"mstr_standard"
BODY_TYPE"PLUMBING";
"B \NAC \NWC"9;
"S \NAC"
BN"1"69;
%"TAP"
"7","(-2300,275)","0","mstr_standard","I276";
;
HDL_TAP"TRUE"
CDS_LIB"mstr_standard"
BODY_TYPE"PLUMBING";
"B \NAC \NWC"9;
"S \NAC"
BN"2"68;
%"CAP"
"1","(-2300,825)","2","mstr_discrete","I277";
;
CDS_SEC"1"
SEC_TYPE"0402"
SEC"1"
CDS_LIB"mstr_discrete"
CDS_LOCATION"C2U7"
TOLERANCE"10%"
LOCATION"C2U7"
VOLTAGE"16V"
VALUE"0.22UF"
PACK_TYPE"0402"
MATERIAL"X7R"
PART_NUMBER"A36096-155";
"A"
$PN"1"64;
"B"
$PN"2"68;
%"CAP"
"1","(-2700,825)","2","mstr_discrete","I278";
;
CDS_SEC"1"
SEC"1"
SEC_TYPE"0402"
CDS_LIB"mstr_discrete"
CDS_LOCATION"C2U11"
TOLERANCE"10%"
VOLTAGE"16V"
MATERIAL"X7R"
VALUE"0.22UF"
PACK_TYPE"0402"
LOCATION"C2U11"
PART_NUMBER"A36096-155";
"A"
$PN"1"66;
"B"
$PN"2"71;
%"CAP"
"1","(-2500,525)","2","mstr_discrete","I279";
;
CDS_SEC"1"
SEC"1"
SEC_TYPE"0402"
CDS_LIB"mstr_discrete"
CDS_LOCATION"C2U9"
PART_NUMBER"A36096-155"
TOLERANCE"10%"
MATERIAL"X7R"
VALUE"0.22UF"
PACK_TYPE"0402"
LOCATION"C2U9"
VOLTAGE"16V";
"A"
$PN"1"65;
"B"
$PN"2"70;
%"TAP"
"7","(-2500,275)","0","mstr_standard","I280";
;
HDL_TAP"TRUE"
BODY_TYPE"PLUMBING"
CDS_LIB"mstr_standard";
"B \NAC \NWC"9;
"S \NAC"
BN"3"70;
%"TAP"
"7","(-2700,275)","0","mstr_standard","I281";
;
HDL_TAP"TRUE"
BODY_TYPE"PLUMBING"
CDS_LIB"mstr_standard";
"B \NAC \NWC"9;
"S \NAC"
BN"4"71;
%"TAP"
"3","(-2950,2075)","0","mstr_standard","I282";
;
CDS_LIB"mstr_standard"
BODY_TYPE"PLUMBING"
HDL_TAP"TRUE";
"B \NAC \NWC"12;
"S \NAC"
BN"5"60;
%"TAP"
"3","(-3150,2075)","0","mstr_standard","I283";
;
CDS_LIB"mstr_standard"
BODY_TYPE"PLUMBING"
HDL_TAP"TRUE";
"B \NAC \NWC"12;
"S \NAC"
BN"6"73;
%"TAP"
"3","(-3350,2075)","0","mstr_standard","I284";
;
CDS_LIB"mstr_standard"
BODY_TYPE"PLUMBING"
HDL_TAP"TRUE";
"B \NAC \NWC"12;
"S \NAC"
BN"7"74;
%"CAP"
"1","(-3150,1825)","2","mstr_discrete","I286";
;
CDS_SEC"1"
SEC"1"
SEC_TYPE"0402"
CDS_LIB"mstr_discrete"
CDS_LOCATION"C2U16"
VOLTAGE"16V"
TOLERANCE"10%"
MATERIAL"X7R"
PACK_TYPE"0402"
LOCATION"C2U16"
VALUE"0.22UF"
PART_NUMBER"A36096-155";
"A"
$PN"1"73;
"B"
$PN"2"75;
%"CAP"
"1","(-2950,1525)","2","mstr_discrete","I287";
;
CDS_SEC"1"
SEC_TYPE"0402"
SEC"1"
CDS_LOCATION"C2U14"
CDS_LIB"mstr_discrete"
PART_NUMBER"A36096-155"
VOLTAGE"16V"
VALUE"0.22UF"
LOCATION"C2U14"
PACK_TYPE"0402"
MATERIAL"X7R"
TOLERANCE"10%";
"A"
$PN"1"60;
"B"
$PN"2"62;
%"TAP"
"3","(-2900,1075)","0","mstr_standard","I288";
;
CDS_LIB"mstr_standard"
BODY_TYPE"PLUMBING"
HDL_TAP"TRUE";
"B \NAC \NWC"10;
"S \NAC"
BN"5"67;
%"TAP"
"7","(-2950,1275)","0","mstr_standard","I289";
;
HDL_TAP"TRUE"
BODY_TYPE"PLUMBING"
CDS_LIB"mstr_standard";
"B \NAC \NWC"11;
"S \NAC"
BN"5"62;
%"TAP"
"7","(-3150,1275)","0","mstr_standard","I290";
;
HDL_TAP"TRUE"
BODY_TYPE"PLUMBING"
CDS_LIB"mstr_standard";
"B \NAC \NWC"11;
"S \NAC"
BN"6"75;
%"TAP"
"3","(-3100,1075)","0","mstr_standard","I291";
;
BODY_TYPE"PLUMBING"
HDL_TAP"TRUE"
CDS_LIB"mstr_standard";
"B \NAC \NWC"10;
"S \NAC"
BN"6"77;
%"TAP"
"7","(-3350,1275)","0","mstr_standard","I292";
;
HDL_TAP"TRUE"
BODY_TYPE"PLUMBING"
CDS_LIB"mstr_standard";
"B \NAC \NWC"11;
"S \NAC"
BN"7"76;
%"TAP"
"3","(-3300,1075)","0","mstr_standard","I293";
;
HDL_TAP"TRUE"
BODY_TYPE"PLUMBING"
CDS_LIB"mstr_standard";
"B \NAC \NWC"10;
"S \NAC"
BN"7"78;
%"CAP"
"1","(-3350,1525)","2","mstr_discrete","I294";
;
CDS_SEC"1"
SEC"1"
SEC_TYPE"0402"
CDS_LOCATION"C2U18"
CDS_LIB"mstr_discrete"
VALUE"0.22UF"
LOCATION"C2U18"
VOLTAGE"16V"
TOLERANCE"10%"
MATERIAL"X7R"
PACK_TYPE"0402"
PART_NUMBER"A36096-155";
"A"
$PN"1"74;
"B"
$PN"2"76;
%"CAP"
"1","(-3100,825)","2","mstr_discrete","I296";
;
CDS_SEC"1"
SEC_TYPE"0402"
SEC"1"
CDS_LOCATION"C2U15"
CDS_LIB"mstr_discrete"
LOCATION"C2U15"
TOLERANCE"10%"
VOLTAGE"16V"
VALUE"0.22UF"
MATERIAL"X7R"
PACK_TYPE"0402"
PART_NUMBER"A36096-155";
"A"
$PN"1"77;
"B"
$PN"2"79;
%"CAP"
"1","(-2900,525)","2","mstr_discrete","I297";
;
CDS_SEC"1"
CDS_LOCATION"C2U13"
CDS_LIB"mstr_discrete"
SEC_TYPE"0402"
SEC"1"
VOLTAGE"16V"
PART_NUMBER"A36096-155"
TOLERANCE"10%"
MATERIAL"X7R"
PACK_TYPE"0402"
VALUE"0.22UF"
LOCATION"C2U13";
"A"
$PN"1"67;
"B"
$PN"2"72;
%"TAP"
"7","(-2900,275)","0","mstr_standard","I298";
;
HDL_TAP"TRUE"
BODY_TYPE"PLUMBING"
CDS_LIB"mstr_standard";
"B \NAC \NWC"9;
"S \NAC"
BN"5"72;
%"TAP"
"7","(-3100,275)","0","mstr_standard","I299";
;
HDL_TAP"TRUE"
BODY_TYPE"PLUMBING"
CDS_LIB"mstr_standard";
"B \NAC \NWC"9;
"S \NAC"
BN"6"79;
%"CAP"
"1","(-3300,525)","2","mstr_discrete","I300";
;
CDS_SEC"1"
CDS_LIB"mstr_discrete"
SEC_TYPE"0402"
SEC"1"
CDS_LOCATION"C2U17"
VOLTAGE"16V"
PART_NUMBER"A36096-155"
LOCATION"C2U17"
VALUE"0.22UF"
TOLERANCE"10%"
PACK_TYPE"0402"
MATERIAL"X7R";
"A"
$PN"1"78;
"B"
$PN"2"80;
%"TAP"
"7","(-3300,275)","0","mstr_standard","I301";
;
HDL_TAP"TRUE"
BODY_TYPE"PLUMBING"
CDS_LIB"mstr_standard";
"B \NAC \NWC"9;
"S \NAC"
BN"7"80;
%"TAP"
"3","(-825,4375)","0","mstr_standard","I355";
;
HDL_TAP"TRUE"
CDS_LIB"mstr_standard"
BODY_TYPE"PLUMBING";
"B \NAC \NWC"16;
"S \NAC"
BN"0"17;
%"TAP"
"3","(-1025,4375)","0","mstr_standard","I356";
;
HDL_TAP"TRUE"
BODY_TYPE"PLUMBING"
CDS_LIB"mstr_standard";
"B \NAC \NWC"16;
"S \NAC"
BN"1"21;
%"TAP"
"3","(-1225,4375)","0","mstr_standard","I357";
;
HDL_TAP"TRUE"
CDS_LIB"mstr_standard"
BODY_TYPE"PLUMBING";
"B \NAC \NWC"16;
"S \NAC"
BN"2"18;
%"TAP"
"3","(-1425,4375)","0","mstr_standard","I359";
;
HDL_TAP"TRUE"
CDS_LIB"mstr_standard"
BODY_TYPE"PLUMBING";
"B \NAC \NWC"16;
"S \NAC"
BN"3"22;
%"TAP"
"3","(-1625,4375)","0","mstr_standard","I360";
;
HDL_TAP"TRUE"
CDS_LIB"mstr_standard"
BODY_TYPE"PLUMBING";
"B \NAC \NWC"16;
"S \NAC"
BN"4"19;
%"TAP"
"3","(-1825,4375)","0","mstr_standard","I361";
;
HDL_TAP"TRUE"
BODY_TYPE"PLUMBING"
CDS_LIB"mstr_standard";
"B \NAC \NWC"16;
"S \NAC"
BN"5"23;
%"TAP"
"3","(-2025,4375)","0","mstr_standard","I363";
;
HDL_TAP"TRUE"
CDS_LIB"mstr_standard"
BODY_TYPE"PLUMBING";
"B \NAC \NWC"16;
"S \NAC"
BN"6"20;
%"TAP"
"3","(-2225,4375)","0","mstr_standard","I365";
;
HDL_TAP"TRUE"
CDS_LIB"mstr_standard"
BODY_TYPE"PLUMBING";
"B \NAC \NWC"16;
"S \NAC"
BN"7"24;
%"TAP"
"7","(-825,3575)","0","mstr_standard","I367";
;
HDL_TAP"TRUE"
BODY_TYPE"PLUMBING"
CDS_LIB"mstr_standard";
"B \NAC \NWC"14;
"S \NAC"
BN"0"25;
%"TAP"
"7","(-1025,3575)","0","mstr_standard","I371";
;
BODY_TYPE"PLUMBING"
HDL_TAP"TRUE"
CDS_LIB"mstr_standard";
"B \NAC \NWC"14;
"S \NAC"
BN"1"31;
%"TAP"
"7","(-1225,3575)","0","mstr_standard","I372";
;
HDL_TAP"TRUE"
BODY_TYPE"PLUMBING"
CDS_LIB"mstr_standard";
"B \NAC \NWC"14;
"S \NAC"
BN"2"30;
%"TAP"
"3","(-800,3350)","0","mstr_standard","I373";
;
HDL_TAP"TRUE"
BODY_TYPE"PLUMBING"
CDS_LIB"mstr_standard";
"B \NAC \NWC"13;
"S \NAC"
BN"0"26;
%"TAP"
"3","(-1000,3350)","0","mstr_standard","I375";
;
HDL_TAP"TRUE"
CDS_LIB"mstr_standard"
BODY_TYPE"PLUMBING";
"B \NAC \NWC"13;
"S \NAC"
BN"1"27;
%"TAP"
"3","(-1200,3350)","0","mstr_standard","I376";
;
HDL_TAP"TRUE"
CDS_LIB"mstr_standard"
BODY_TYPE"PLUMBING";
"B \NAC \NWC"13;
"S \NAC"
BN"2"33;
%"TAP"
"7","(-1425,3575)","0","mstr_standard","I379";
;
BODY_TYPE"PLUMBING"
CDS_LIB"mstr_standard"
HDL_TAP"TRUE";
"B \NAC \NWC"14;
"S \NAC"
BN"3"32;
%"TAP"
"7","(-1625,3575)","0","mstr_standard","I380";
;
HDL_TAP"TRUE"
BODY_TYPE"PLUMBING"
CDS_LIB"mstr_standard";
"B \NAC \NWC"14;
"S \NAC"
BN"4"34;
%"TAP"
"7","(-1825,3575)","0","mstr_standard","I382";
;
HDL_TAP"TRUE"
BODY_TYPE"PLUMBING"
CDS_LIB"mstr_standard";
"B \NAC \NWC"14;
"S \NAC"
BN"5"36;
%"TAP"
"3","(-1400,3350)","0","mstr_standard","I383";
;
HDL_TAP"TRUE"
CDS_LIB"mstr_standard"
BODY_TYPE"PLUMBING";
"B \NAC \NWC"13;
"S \NAC"
BN"3"39;
%"TAP"
"3","(-1600,3350)","0","mstr_standard","I384";
;
HDL_TAP"TRUE"
CDS_LIB"mstr_standard"
BODY_TYPE"PLUMBING";
"B \NAC \NWC"13;
"S \NAC"
BN"4"37;
%"TAP"
"7","(-800,2550)","0","mstr_standard","I386";
;
HDL_TAP"TRUE"
BODY_TYPE"PLUMBING"
CDS_LIB"mstr_standard";
"B \NAC \NWC"15;
"S \NAC"
BN"0"28;
%"TAP"
"7","(-1000,2550)","0","mstr_standard","I388";
;
BODY_TYPE"PLUMBING"
CDS_LIB"mstr_standard"
HDL_TAP"TRUE";
"B \NAC \NWC"15;
"S \NAC"
BN"1"29;
%"TAP"
"7","(-1200,2550)","0","mstr_standard","I389";
;
HDL_TAP"TRUE"
BODY_TYPE"PLUMBING"
CDS_LIB"mstr_standard";
"B \NAC \NWC"15;
"S \NAC"
BN"2"41;
%"TAP"
"7","(-1400,2550)","0","mstr_standard","I391";
;
BODY_TYPE"PLUMBING"
CDS_LIB"mstr_standard"
HDL_TAP"TRUE";
"B \NAC \NWC"15;
"S \NAC"
BN"3"42;
%"TAP"
"7","(-1600,2550)","0","mstr_standard","I392";
;
HDL_TAP"TRUE"
BODY_TYPE"PLUMBING"
CDS_LIB"mstr_standard";
"B \NAC \NWC"15;
"S \NAC"
BN"4"43;
%"TAP"
"7","(-2025,3575)","0","mstr_standard","I393";
;
BODY_TYPE"PLUMBING"
CDS_LIB"mstr_standard"
HDL_TAP"TRUE";
"B \NAC \NWC"14;
"S \NAC"
BN"6"35;
%"TAP"
"7","(-2225,3575)","0","mstr_standard","I395";
;
HDL_TAP"TRUE"
BODY_TYPE"PLUMBING"
CDS_LIB"mstr_standard";
"B \NAC \NWC"14;
"S \NAC"
BN"7"50;
%"TAP"
"3","(-1800,3350)","0","mstr_standard","I396";
;
HDL_TAP"TRUE"
BODY_TYPE"PLUMBING"
CDS_LIB"mstr_standard";
"B \NAC \NWC"13;
"S \NAC"
BN"5"40;
%"TAP"
"3","(-2000,3350)","0","mstr_standard","I397";
;
HDL_TAP"TRUE"
CDS_LIB"mstr_standard"
BODY_TYPE"PLUMBING";
"B \NAC \NWC"13;
"S \NAC"
BN"6"38;
%"TAP"
"3","(-2200,3350)","0","mstr_standard","I399";
;
HDL_TAP"TRUE"
CDS_LIB"mstr_standard"
BODY_TYPE"PLUMBING";
"B \NAC \NWC"13;
"S \NAC"
BN"7"51;
%"TAP"
"7","(-1800,2550)","0","mstr_standard","I402";
;
HDL_TAP"TRUE"
BODY_TYPE"PLUMBING"
CDS_LIB"mstr_standard";
"B \NAC \NWC"15;
"S \NAC"
BN"5"45;
%"TAP"
"7","(-2000,2550)","0","mstr_standard","I403";
;
BODY_TYPE"PLUMBING"
CDS_LIB"mstr_standard"
HDL_TAP"TRUE";
"B \NAC \NWC"15;
"S \NAC"
BN"6"44;
%"TAP"
"7","(-2200,2550)","0","mstr_standard","I405";
;
HDL_TAP"TRUE"
BODY_TYPE"PLUMBING"
CDS_LIB"mstr_standard";
"B \NAC \NWC"15;
"S \NAC"
BN"7"52;
%"TAP"
"7","(-5450,2425)","0","mstr_standard","I406";
;
HDL_TAP"TRUE"
CDS_LIB"mstr_standard"
BODY_TYPE"PLUMBING";
"B \NAC \NWC"5;
"S \NAC"
BN"6"111;
%"TAP"
"3","(-4300,4225)","0","mstr_standard","I407";
;
HDL_TAP"TRUE"
BODY_TYPE"PLUMBING"
CDS_LIB"mstr_standard";
"B \NAC \NWC"8;
"S \NAC"
BN"0"82;
%"TAP"
"3","(-4500,4225)","0","mstr_standard","I408";
;
BODY_TYPE"PLUMBING"
CDS_LIB"mstr_standard"
HDL_TAP"TRUE";
"B \NAC \NWC"8;
"S \NAC"
BN"1"83;
%"TAP"
"3","(-4700,4225)","0","mstr_standard","I409";
;
BODY_TYPE"PLUMBING"
CDS_LIB"mstr_standard"
HDL_TAP"TRUE";
"B \NAC \NWC"8;
"S \NAC"
BN"2"84;
%"TAP"
"3","(-4900,4225)","0","mstr_standard","I410";
;
BODY_TYPE"PLUMBING"
CDS_LIB"mstr_standard"
HDL_TAP"TRUE";
"B \NAC \NWC"8;
"S \NAC"
BN"3"85;
%"TAP"
"3","(-5100,4225)","0","mstr_standard","I411";
;
BODY_TYPE"PLUMBING"
CDS_LIB"mstr_standard"
HDL_TAP"TRUE";
"B \NAC \NWC"8;
"S \NAC"
BN"4"86;
%"TAP"
"3","(-5300,4225)","0","mstr_standard","I412";
;
BODY_TYPE"PLUMBING"
CDS_LIB"mstr_standard"
HDL_TAP"TRUE";
"B \NAC \NWC"8;
"S \NAC"
BN"5"87;
%"TAP"
"3","(-5500,4225)","0","mstr_standard","I413";
;
BODY_TYPE"PLUMBING"
CDS_LIB"mstr_standard"
HDL_TAP"TRUE";
"B \NAC \NWC"8;
"S \NAC"
BN"6"81;
%"TAP"
"3","(-5700,4225)","0","mstr_standard","I414";
;
BODY_TYPE"PLUMBING"
CDS_LIB"mstr_standard"
HDL_TAP"TRUE";
"B \NAC \NWC"8;
"S \NAC"
BN"7"88;
%"CAP"
"1","(-4300,3975)","2","mstr_discrete","I415";
;
$SEC"1"
CDS_SEC"1"
CDS_LOCATION"C3P12"
CDS_LIB"mstr_discrete"
LOCATION"C3P12"
VOLTAGE"16V"
PACK_TYPE"0402"
TOLERANCE"10%"
VALUE"0.22UF"
MATERIAL"EMPTY"
PART_NUMBER"A36096-155";
"A"
$PN"1"82;
"B"
$PN"2"89;
%"CAP"
"1","(-4250,2975)","2","mstr_discrete","I417";
;
$SEC"1"
CDS_SEC"1"
CDS_LOCATION"C3P10"
CDS_LIB"mstr_discrete"
LOCATION"C3P10"
VOLTAGE"16V"
PACK_TYPE"0402"
TOLERANCE"10%"
VALUE"0.22UF"
PART_NUMBER"A36096-155"
MATERIAL"EMPTY";
"A"
$PN"1"91;
"B"
$PN"2"99;
%"TAP"
"7","(-4300,3425)","0","mstr_standard","I418";
;
HDL_TAP"TRUE"
BODY_TYPE"PLUMBING"
CDS_LIB"mstr_standard";
"B \NAC \NWC"7;
"S \NAC"
BN"0"89;
%"TAP"
"3","(-4250,3225)","0","mstr_standard","I419";
;
HDL_TAP"TRUE"
BODY_TYPE"PLUMBING"
CDS_LIB"mstr_standard";
"B \NAC \NWC"6;
"S \NAC"
BN"0"91;
%"TAP"
"3","(-4450,3225)","0","mstr_standard","I420";
;
HDL_TAP"TRUE"
BODY_TYPE"PLUMBING"
CDS_LIB"mstr_standard";
"B \NAC \NWC"6;
"S \NAC"
BN"1"97;
%"TAP"
"7","(-4500,3425)","0","mstr_standard","I421";
;
HDL_TAP"TRUE"
BODY_TYPE"PLUMBING"
CDS_LIB"mstr_standard";
"B \NAC \NWC"7;
"S \NAC"
BN"1"90;
%"CAP"
"1","(-4500,3700)","2","mstr_discrete","I422";
;
$SEC"1"
CDS_SEC"1"
CDS_LOCATION"C3P16"
CDS_LIB"mstr_discrete"
VOLTAGE"16V"
PACK_TYPE"0402"
TOLERANCE"10%"
VALUE"0.22UF"
PART_NUMBER"A36096-155"
LOCATION"C3P16"
MATERIAL"EMPTY";
"A"
$PN"1"83;
"B"
$PN"2"90;
%"CAP"
"1","(-4700,3975)","2","mstr_discrete","I423";
;
$SEC"1"
CDS_SEC"1"
CDS_LOCATION"C3P21"
CDS_LIB"mstr_discrete"
LOCATION"C3P21"
VOLTAGE"16V"
TOLERANCE"10%"
PACK_TYPE"0402"
VALUE"0.22UF"
PART_NUMBER"A36096-155"
MATERIAL"EMPTY";
"A"
$PN"1"84;
"B"
$PN"2"92;
%"CAP"
"1","(-4900,3675)","2","mstr_discrete","I424";
;
$SEC"1"
CDS_SEC"1"
CDS_LOCATION"C3P24"
CDS_LIB"mstr_discrete"
VOLTAGE"16V"
TOLERANCE"10%"
LOCATION"C3P24"
MATERIAL"EMPTY"
PACK_TYPE"0402"
VALUE"0.22UF"
PART_NUMBER"A36096-155";
"A"
$PN"1"85;
"B"
$PN"2"95;
%"TAP"
"3","(-4650,3225)","0","mstr_standard","I425";
;
HDL_TAP"TRUE"
BODY_TYPE"PLUMBING"
CDS_LIB"mstr_standard";
"B \NAC \NWC"6;
"S \NAC"
BN"2"94;
%"TAP"
"7","(-4700,3425)","0","mstr_standard","I426";
;
HDL_TAP"TRUE"
BODY_TYPE"PLUMBING"
CDS_LIB"mstr_standard";
"B \NAC \NWC"7;
"S \NAC"
BN"2"92;
%"CAP"
"1","(-4650,2975)","2","mstr_discrete","I427";
;
$SEC"1"
CDS_SEC"1"
CDS_LOCATION"C3P19"
CDS_LIB"mstr_discrete"
LOCATION"C3P19"
VOLTAGE"16V"
TOLERANCE"10%"
MATERIAL"EMPTY"
PACK_TYPE"0402"
VALUE"0.22UF"
PART_NUMBER"A36096-155";
"A"
$PN"1"94;
"B"
$PN"2"101;
%"TAP"
"3","(-4850,3225)","0","mstr_standard","I428";
;
HDL_TAP"TRUE"
CDS_LIB"mstr_standard"
BODY_TYPE"PLUMBING";
"B \NAC \NWC"6;
"S \NAC"
BN"3"98;
%"TAP"
"7","(-4900,3425)","0","mstr_standard","I429";
;
HDL_TAP"TRUE"
BODY_TYPE"PLUMBING"
CDS_LIB"mstr_standard";
"B \NAC \NWC"7;
"S \NAC"
BN"3"95;
%"TAP"
"7","(-4250,2425)","0","mstr_standard","I430";
;
HDL_TAP"TRUE"
BODY_TYPE"PLUMBING"
CDS_LIB"mstr_standard";
"B \NAC \NWC"5;
"S \NAC"
BN"0"99;
%"CAP"
"1","(-4450,2675)","2","mstr_discrete","I431";
;
$SEC"1"
CDS_SEC"1"
CDS_LIB"mstr_discrete"
CDS_LOCATION"C3P14"
VOLTAGE"16V"
TOLERANCE"10%"
PACK_TYPE"0402"
VALUE"0.22UF"
PART_NUMBER"A36096-155"
LOCATION"C3P14"
MATERIAL"EMPTY";
"A"
$PN"1"97;
"B"
$PN"2"100;
%"TAP"
"7","(-4450,2425)","0","mstr_standard","I432";
;
HDL_TAP"TRUE"
BODY_TYPE"PLUMBING"
CDS_LIB"mstr_standard";
"B \NAC \NWC"5;
"S \NAC"
BN"1"100;
%"TAP"
"7","(-4650,2425)","0","mstr_standard","I434";
;
HDL_TAP"TRUE"
BODY_TYPE"PLUMBING"
CDS_LIB"mstr_standard";
"B \NAC \NWC"5;
"S \NAC"
BN"2"101;
%"CAP"
"1","(-4850,2675)","2","mstr_discrete","I435";
;
CDS_LIB"mstr_discrete"
$SEC"1"
CDS_SEC"1"
CDS_LOCATION"C3P22"
VOLTAGE"16V"
TOLERANCE"10%"
VALUE"0.22UF"
LOCATION"C3P22"
MATERIAL"EMPTY"
PACK_TYPE"0402"
PART_NUMBER"A36096-155";
"A"
$PN"1"98;
"B"
$PN"2"102;
%"TAP"
"7","(-4850,2425)","0","mstr_standard","I436";
;
HDL_TAP"TRUE"
BODY_TYPE"PLUMBING"
CDS_LIB"mstr_standard";
"B \NAC \NWC"5;
"S \NAC"
BN"3"102;
%"CAP"
"1","(-5100,3975)","2","mstr_discrete","I437";
;
$SEC"1"
CDS_SEC"1"
CDS_LOCATION"C3P29"
CDS_LIB"mstr_discrete"
LOCATION"C3P29"
VOLTAGE"16V"
TOLERANCE"10%"
VALUE"0.22UF"
MATERIAL"EMPTY"
PACK_TYPE"0402"
PART_NUMBER"A36096-155";
"A"
$PN"1"86;
"B"
$PN"2"93;
%"CAP"
"1","(-5500,3975)","2","mstr_discrete","I438";
;
$SEC"1"
CDS_SEC"1"
CDS_LOCATION"C3P36"
CDS_LIB"mstr_discrete"
LOCATION"C3P36"
VOLTAGE"16V"
PACK_TYPE"0402"
TOLERANCE"10%"
VALUE"0.22UF"
PART_NUMBER"A36096-155"
MATERIAL"EMPTY";
"A"
$PN"1"81;
"B"
$PN"2"104;
%"CAP"
"1","(-5300,3675)","2","mstr_discrete","I439";
;
$SEC"1"
CDS_SEC"1"
CDS_LOCATION"C3P33"
CDS_LIB"mstr_discrete"
VOLTAGE"16V"
TOLERANCE"10%"
VALUE"0.22UF"
LOCATION"C3P33"
MATERIAL"EMPTY"
PACK_TYPE"0402"
PART_NUMBER"A36096-155";
"A"
$PN"1"87;
"B"
$PN"2"105;
%"TAP"
"7","(-5100,3425)","0","mstr_standard","I440";
;
HDL_TAP"TRUE"
BODY_TYPE"PLUMBING"
CDS_LIB"mstr_standard";
"B \NAC \NWC"7;
"S \NAC"
BN"4"93;
%"TAP"
"3","(-5050,3225)","0","mstr_standard","I441";
;
HDL_TAP"TRUE"
CDS_LIB"mstr_standard"
BODY_TYPE"PLUMBING";
"B \NAC \NWC"6;
"S \NAC"
BN"4"96;
%"TAP"
"7","(-5300,3425)","0","mstr_standard","I442";
;
HDL_TAP"TRUE"
BODY_TYPE"PLUMBING"
CDS_LIB"mstr_standard";
"B \NAC \NWC"7;
"S \NAC"
BN"5"105;
%"TAP"
"3","(-5250,3225)","0","mstr_standard","I443";
;
HDL_TAP"TRUE"
BODY_TYPE"PLUMBING"
CDS_LIB"mstr_standard";
"B \NAC \NWC"6;
"S \NAC"
BN"5"108;
%"CAP"
"1","(-5050,2975)","2","mstr_discrete","I444";
;
$SEC"1"
CDS_SEC"1"
CDS_LOCATION"C3P26"
CDS_LIB"mstr_discrete"
VOLTAGE"16V"
PACK_TYPE"0402"
TOLERANCE"10%"
VALUE"0.22UF"
PART_NUMBER"A36096-155"
LOCATION"C3P26"
MATERIAL"EMPTY";
"A"
$PN"1"96;
"B"
$PN"2"103;
%"TAP"
"7","(-5500,3425)","0","mstr_standard","I445";
;
HDL_TAP"TRUE"
BODY_TYPE"PLUMBING"
CDS_LIB"mstr_standard";
"B \NAC \NWC"7;
"S \NAC"
BN"6"104;
%"TAP"
"3","(-5450,3225)","0","mstr_standard","I446";
;
HDL_TAP"TRUE"
CDS_LIB"mstr_standard"
BODY_TYPE"PLUMBING";
"B \NAC \NWC"6;
"S \NAC"
BN"6"106;
%"CAP"
"1","(-5450,2975)","2","mstr_discrete","I447";
;
CDS_SEC"1"
$SEC"1"
CDS_LOCATION"C3P34"
CDS_LIB"mstr_discrete"
LOCATION"C3P34"
VOLTAGE"16V"
TOLERANCE"10%"
PACK_TYPE"0402"
VALUE"0.22UF"
PART_NUMBER"A36096-155"
MATERIAL"EMPTY";
"A"
$PN"1"106;
"B"
$PN"2"111;
%"CAP"
"1","(-5700,3675)","2","mstr_discrete","I448";
;
$SEC"1"
CDS_SEC"1"
CDS_LOCATION"C3P41"
CDS_LIB"mstr_discrete"
VOLTAGE"16V"
TOLERANCE"10%"
VALUE"0.22UF"
LOCATION"C3P41"
MATERIAL"EMPTY"
PACK_TYPE"0402"
PART_NUMBER"A36096-155";
"A"
$PN"1"88;
"B"
$PN"2"107;
%"TAP"
"3","(-5650,3225)","0","mstr_standard","I449";
;
HDL_TAP"TRUE"
BODY_TYPE"PLUMBING"
CDS_LIB"mstr_standard";
"B \NAC \NWC"6;
"S \NAC"
BN"7"109;
%"TAP"
"7","(-5700,3425)","0","mstr_standard","I450";
;
HDL_TAP"TRUE"
BODY_TYPE"PLUMBING"
CDS_LIB"mstr_standard";
"B \NAC \NWC"7;
"S \NAC"
BN"7"107;
%"TAP"
"7","(-5050,2425)","0","mstr_standard","I451";
;
HDL_TAP"TRUE"
BODY_TYPE"PLUMBING"
CDS_LIB"mstr_standard";
"B \NAC \NWC"5;
"S \NAC"
BN"4"103;
%"CAP"
"1","(-5250,2675)","2","mstr_discrete","I452";
;
$SEC"1"
CDS_SEC"1"
CDS_LOCATION"C3P31"
CDS_LIB"mstr_discrete"
VOLTAGE"16V"
TOLERANCE"10%"
VALUE"0.22UF"
LOCATION"C3P31"
MATERIAL"EMPTY"
PACK_TYPE"0402"
PART_NUMBER"A36096-155";
"A"
$PN"1"108;
"B"
$PN"2"110;
%"TAP"
"7","(-5250,2425)","0","mstr_standard","I453";
;
HDL_TAP"TRUE"
BODY_TYPE"PLUMBING"
CDS_LIB"mstr_standard";
"B \NAC \NWC"5;
"S \NAC"
BN"5"110;
%"TAP"
"7","(-5650,2425)","0","mstr_standard","I454";
;
HDL_TAP"TRUE"
BODY_TYPE"PLUMBING"
CDS_LIB"mstr_standard";
"B \NAC \NWC"5;
"S \NAC"
BN"7"112;
%"CAP"
"1","(-5650,2675)","2","mstr_discrete","I455";
;
$SEC"1"
CDS_SEC"1"
CDS_LOCATION"C3P38"
CDS_LIB"mstr_discrete"
VOLTAGE"16V"
TOLERANCE"10%"
VALUE"0.22UF"
LOCATION"C3P38"
MATERIAL"EMPTY"
PACK_TYPE"0402"
PART_NUMBER"A36096-155";
"A"
$PN"1"109;
"B"
$PN"2"112;
%"RES"
"2","(-2225,3825)","0","mstr_discrete","I458";
;
$SEC"1"
CDS_SEC"1"
CDS_LOCATION"R2U29"
CDS_LIB"mstr_discrete"
WATTAGE"1/16W"
PART_NUMBER"G21497-005"
LOCATION"R2U29"
MATERIAL"EMPTY"
TOLERANCE"5%"
VALUE"0.0"
PACK_TYPE"0402";
"A"
$PN"1"24;
"B"
$PN"2"50;
%"RES"
"2","(-2025,4125)","0","mstr_discrete","I459";
;
$SEC"1"
CDS_SEC"1"
CDS_LOCATION"R2U27"
CDS_LIB"mstr_discrete"
WATTAGE"1/16W"
VALUE"0.0"
LOCATION"R2U27"
TOLERANCE"5%"
PART_NUMBER"G21497-005"
PACK_TYPE"0402"
MATERIAL"EMPTY";
"A"
$PN"1"20;
"B"
$PN"2"35;
%"RES"
"2","(-1825,3825)","0","mstr_discrete","I460";
;
CDS_SEC"1"
$SEC"1"
CDS_LOCATION"R2U25"
CDS_LIB"mstr_discrete"
PART_NUMBER"G21497-005"
LOCATION"R2U25"
VALUE"0.0"
TOLERANCE"5%"
MATERIAL"EMPTY"
WATTAGE"1/16W"
PACK_TYPE"0402";
"A"
$PN"1"23;
"B"
$PN"2"36;
%"RES"
"2","(-1625,4125)","0","mstr_discrete","I461";
;
$SEC"1"
CDS_SEC"1"
CDS_LOCATION"R2U23"
CDS_LIB"mstr_discrete"
WATTAGE"1/16W"
TOLERANCE"5%"
VALUE"0.0"
LOCATION"R2U23"
PACK_TYPE"0402"
PART_NUMBER"G21497-005"
MATERIAL"EMPTY";
"A"
$PN"1"19;
"B"
$PN"2"34;
%"RES"
"2","(-1425,3825)","0","mstr_discrete","I462";
;
CDS_SEC"1"
$SEC"1"
CDS_LOCATION"R2U21"
CDS_LIB"mstr_discrete"
WATTAGE"1/16W"
PACK_TYPE"0402"
PART_NUMBER"G21497-005"
LOCATION"R2U21"
MATERIAL"EMPTY"
VALUE"0.0"
TOLERANCE"5%";
"A"
$PN"1"22;
"B"
$PN"2"32;
%"RES"
"2","(-1225,4125)","0","mstr_discrete","I463";
;
$SEC"1"
CDS_SEC"1"
CDS_LOCATION"R2U19"
CDS_LIB"mstr_discrete"
WATTAGE"1/16W"
TOLERANCE"5%"
VALUE"0.0"
LOCATION"R2U19"
PART_NUMBER"G21497-005"
PACK_TYPE"0402"
MATERIAL"EMPTY";
"A"
$PN"1"18;
"B"
$PN"2"30;
%"RES"
"2","(-1025,3825)","0","mstr_discrete","I464";
;
CDS_SEC"1"
$SEC"1"
CDS_LOCATION"R2U17"
CDS_LIB"mstr_discrete"
PART_NUMBER"G21497-005"
VALUE"0.0"
LOCATION"R2U17"
TOLERANCE"5%"
WATTAGE"1/16W"
PACK_TYPE"0402"
MATERIAL"EMPTY";
"A"
$PN"1"21;
"B"
$PN"2"31;
%"RES"
"2","(-825,4125)","0","mstr_discrete","I465";
;
$SEC"1"
CDS_SEC"1"
CDS_LOCATION"R2U15"
CDS_LIB"mstr_discrete"
WATTAGE"1/16W"
TOLERANCE"5%"
VALUE"0.0"
LOCATION"R2U15"
PART_NUMBER"G21497-005"
PACK_TYPE"0402"
MATERIAL"EMPTY";
"A"
$PN"1"17;
"B"
$PN"2"25;
%"RES"
"2","(-800,3100)","0","mstr_discrete","I466";
;
$SEC"1"
CDS_SEC"1"
CDS_LOCATION"R2U14"
CDS_LIB"mstr_discrete"
LOCATION"R2U14"
WATTAGE"1/16W"
VALUE"0.0"
TOLERANCE"5%"
PART_NUMBER"G21497-005"
PACK_TYPE"0402"
MATERIAL"EMPTY";
"A"
$PN"1"26;
"B"
$PN"2"28;
%"RES"
"2","(-1000,2800)","0","mstr_discrete","I467";
;
$SEC"1"
CDS_SEC"1"
CDS_LOCATION"R2U16"
CDS_LIB"mstr_discrete"
PART_NUMBER"G21497-005"
VALUE"0.0"
LOCATION"R2U16"
TOLERANCE"5%"
WATTAGE"1/16W"
PACK_TYPE"0402"
MATERIAL"EMPTY";
"A"
$PN"1"27;
"B"
$PN"2"29;
%"RES"
"2","(-1200,3100)","0","mstr_discrete","I468";
;
$SEC"1"
CDS_SEC"1"
CDS_LOCATION"R2U18"
CDS_LIB"mstr_discrete"
WATTAGE"1/16W"
PART_NUMBER"G21497-005"
LOCATION"R2U18"
MATERIAL"EMPTY"
TOLERANCE"5%"
VALUE"0.0"
PACK_TYPE"0402";
"A"
$PN"1"33;
"B"
$PN"2"41;
%"RES"
"2","(-1400,2800)","0","mstr_discrete","I469";
;
CDS_SEC"1"
$SEC"1"
CDS_LOCATION"R2U20"
CDS_LIB"mstr_discrete"
WATTAGE"1/16W"
PACK_TYPE"0402"
VALUE"0.0"
PART_NUMBER"G21497-005"
LOCATION"R2U20"
MATERIAL"EMPTY"
TOLERANCE"5%";
"A"
$PN"1"39;
"B"
$PN"2"42;
%"RES"
"2","(-1600,3100)","0","mstr_discrete","I470";
;
$SEC"1"
CDS_SEC"1"
CDS_LOCATION"R2U22"
CDS_LIB"mstr_discrete"
WATTAGE"1/16W"
TOLERANCE"5%"
VALUE"0.0"
LOCATION"R2U22"
PACK_TYPE"0402"
PART_NUMBER"G21497-005"
MATERIAL"EMPTY";
"A"
$PN"1"37;
"B"
$PN"2"43;
%"RES"
"2","(-1800,2800)","0","mstr_discrete","I471";
;
CDS_LOCATION"R2U24"
$SEC"1"
CDS_SEC"1"
CDS_LIB"mstr_discrete"
PART_NUMBER"G21497-005"
LOCATION"R2U24"
TOLERANCE"5%"
VALUE"0.0"
MATERIAL"EMPTY"
PACK_TYPE"0402"
WATTAGE"1/16W";
"A"
$PN"1"40;
"B"
$PN"2"45;
%"RES"
"2","(-2000,3100)","0","mstr_discrete","I472";
;
$SEC"1"
CDS_SEC"1"
CDS_LOCATION"R2U26"
CDS_LIB"mstr_discrete"
WATTAGE"1/16W"
TOLERANCE"5%"
VALUE"0.0"
LOCATION"R2U26"
PART_NUMBER"G21497-005"
PACK_TYPE"0402"
MATERIAL"EMPTY";
"A"
$PN"1"38;
"B"
$PN"2"44;
%"RES"
"2","(-2200,2800)","0","mstr_discrete","I473";
;
CDS_SEC"1"
$SEC"1"
CDS_LOCATION"R2U28"
CDS_LIB"mstr_discrete"
WATTAGE"1/16W"
PACK_TYPE"0402"
PART_NUMBER"G21497-005"
LOCATION"R2U28"
MATERIAL"EMPTY"
VALUE"0.0"
TOLERANCE"5%";
"A"
$PN"1"51;
"B"
$PN"2"52;
END.
